# S9S_MB_2U (Grand Teton) — schematic netlist excerpt (pin names and nets, part order shuffled) for the footprints in the layout excerpt that follows; sources: Cadence DE-HDL packaged netlist, KiCad conversion of 03242023_DA0F0TMBIJ0_F0T_Motherboard_J_brd_V01_OCP.brd

PR3835  Q_RES  14.3K 1% CHIP  pkg 0402LF  page 157 : A = P12V_OCP_ISET_1 ; B = GND
PC1650  Q_CAP  100NF 50V 10% X7R  pkg C0402  page 262 : A = P12V_AUX ; B = GND

(kicad_pcb
	(version 20260206)
	(generator "pcbnew")
	(generator_version "10.0")
	(general
		(thickness 1.6)
		(legacy_teardrops no)
	)
	(paper "A4")
	(title_block
		(title "03242023_DA0F0TMBIJ0_F0T_Motherboard_J_brd_V01_OCP.brd")
		(comment 1 "Grand Teton / footprints 2204-2205 of 6105")
	)
	(layers
		(0 "F.Cu" signal "TOP")
		(4 "In1.Cu" signal "GND")
		(6 "In2.Cu" signal "IN1")
		(8 "In3.Cu" signal "GND1")
		(10 "In4.Cu" signal "IN2")
		(12 "In5.Cu" signal "GND2")
		(14 "In6.Cu" signal "IN3")
		(16 "In7.Cu" signal "GND3")
		(18 "In8.Cu" signal "VCC")
		(20 "In9.Cu" signal "VCC1")
		(22 "In10.Cu" signal "GND4")
		(24 "In11.Cu" signal "IN4")
		(26 "In12.Cu" signal "GND5")
		(28 "In13.Cu" signal "IN5")
		(30 "In14.Cu" signal "GND6")
		(32 "In15.Cu" signal "IN6")
		(34 "In16.Cu" signal "GND7")
		(2 "B.Cu" signal "BOTTOM")
		(9 "F.Adhes" user "F.Adhesive")
		(11 "B.Adhes" user "B.Adhesive")
		(13 "F.Paste" user "Package Geometry/Pastemask Top")
		(15 "B.Paste" user "Package Geometry/Pastemask Bottom")
		(5 "F.SilkS" user "Ref Des/Silkscreen Top")
		(7 "B.SilkS" user "Ref Des/Silkscreen Bottom")
		(1 "F.Mask" user "Board Geometry/Soldermask Top")
		(3 "B.Mask" user "Board Geometry/Soldermask Bottom")
		(17 "Dwgs.User" user "User.Drawings")
		(19 "Cmts.User" user "User.Comments")
		(21 "Eco1.User" user "User.Eco1")
		(23 "Eco2.User" user "User.Eco2")
		(25 "Edge.Cuts" user "Board Geometry/Outline")
		(27 "Margin" user)
		(31 "F.CrtYd" user "Package Geometry/Place Bound Top")
		(29 "B.CrtYd" user "Package Geometry/Place Bound Bottom")
		(35 "F.Fab" user "Ref Des/Assembly Top")
		(33 "B.Fab" user "Ref Des/Assembly Bottom")
	)
	(footprint ""
		(layer "F.Cu")
		(at 249.643646 -70.204076)
		(property "Reference" "PC1650"
			(at 0 0 0)
			(layer "F.SilkS")
			(hide yes)
			(effects
				(font
					(size 1.27 1.27)
				)
			)
		)
		(property "Value" ""
			(at 0 0 0)
			(layer "F.Fab")
			(effects
				(font
					(size 1.27 1.27)
				)
			)
		)
		(duplicate_pad_numbers_are_jumpers no)
		(fp_line
			(start -0.7874 -0.4064)
			(end 0.7874 -0.4064)
			(stroke
				(width 0.1524)
				(type default)
			)
			(layer "F.SilkS")
		)
		(fp_line
			(start -0.7874 0.4064)
			(end -0.7874 -0.4064)
			(stroke
				(width 0.1524)
				(type default)
			)
			(layer "F.SilkS")
		)
		(fp_line
			(start 0.7874 -0.4064)
			(end 0.7874 0.4064)
			(stroke
				(width 0.1524)
				(type default)
			)
			(layer "F.SilkS")
		)
		(fp_line
			(start 0.7874 0.4064)
			(end -0.7874 0.4064)
			(stroke
				(width 0.1524)
				(type default)
			)
			(layer "F.SilkS")
		)
		(fp_line
			(start -0.67945 -0.305054)
			(end -0.12065 -0.305054)
			(stroke
				(width 0.1)
				(type default)
			)
			(layer "F.Fab")
		)
		(fp_line
			(start -0.67945 0.3048)
			(end -0.67945 -0.305054)
			(stroke
				(width 0.1)
				(type default)
			)
			(layer "F.Fab")
		)
		(fp_line
			(start -0.12065 -0.305054)
			(end -0.12065 -0.2794)
			(stroke
				(width 0.1)
				(type default)
			)
			(layer "F.Fab")
		)
		(fp_line
			(start -0.12065 -0.2794)
			(end 0.12065 -0.2794)
			(stroke
				(width 0.1)
				(type default)
			)
			(layer "F.Fab")
		)
		(fp_line
			(start -0.12065 0.2794)
			(end -0.12065 0.3048)
			(stroke
				(width 0.1)
				(type default)
			)
			(layer "F.Fab")
		)
		(fp_line
			(start -0.12065 0.3048)
			(end -0.67945 0.3048)
			(stroke
				(width 0.1)
				(type default)
			)
			(layer "F.Fab")
		)
		(fp_line
			(start 0.120396 0.2794)
			(end -0.12065 0.2794)
			(stroke
				(width 0.1)
				(type default)
			)
			(layer "F.Fab")
		)
		(fp_line
			(start 0.120396 0.3048)
			(end 0.120396 0.2794)
			(stroke
				(width 0.1)
				(type default)
			)
			(layer "F.Fab")
		)
		(fp_line
			(start 0.12065 -0.3048)
			(end 0.67945 -0.3048)
			(stroke
				(width 0.1)
				(type default)
			)
			(layer "F.Fab")
		)
		(fp_line
			(start 0.12065 -0.2794)
			(end 0.12065 -0.3048)
			(stroke
				(width 0.1)
				(type default)
			)
			(layer "F.Fab")
		)
		(fp_line
			(start 0.67945 -0.3048)
			(end 0.67945 0.3048)
			(stroke
				(width 0.1)
				(type default)
			)
			(layer "F.Fab")
		)
		(fp_line
			(start 0.67945 0.3048)
			(end 0.120396 0.3048)
			(stroke
				(width 0.1)
				(type default)
			)
			(layer "F.Fab")
		)
		(pad "1" smd circle
			(at -0.40005 0)
			(size 0 0)
			(layers "F.Cu" "F.Mask" "F.Paste")
			(net "P12V_AUX")
		)
		(pad "2" smd circle
			(at 0.40005 0)
			(size 0 0)
			(layers "F.Cu" "F.Mask" "F.Paste")
			(net "GND")
		)
	)
	(footprint ""
		(layer "F.Cu")
		(at 442.828172 -33.062418 90)
		(property "Reference" "PR3835"
			(at 0 0 90)
			(layer "F.SilkS")
			(hide yes)
			(effects
				(font
					(size 1.27 1.27)
				)
			)
		)
		(property "Value" ""
			(at 0 0 90)
			(layer "F.Fab")
			(effects
				(font
					(size 1.27 1.27)
				)
			)
		)
		(duplicate_pad_numbers_are_jumpers no)
		(fp_line
			(start 0.7874 -0.4064)
			(end 0.7874 0.4064)
			(stroke
				(width 0.1524)
				(type default)
			)
			(layer "F.SilkS")
		)
		(fp_line
			(start -0.7874 -0.4064)
			(end 0.7874 -0.4064)
			(stroke
				(width 0.1524)
				(type default)
			)
			(layer "F.SilkS")
		)
		(fp_line
			(start 0.7874 0.4064)
			(end -0.7874 0.4064)
			(stroke
				(width 0.1524)
				(type default)
			)
			(layer "F.SilkS")
		)
		(fp_line
			(start -0.7874 0.4064)
			(end -0.7874 -0.4064)
			(stroke
				(width 0.1524)
				(type default)
			)
			(layer "F.SilkS")
		)
		(fp_line
			(start -0.12065 -0.305054)
			(end -0.12065 -0.2794)
			(stroke
				(width 0.1)
				(type default)
			)
			(layer "F.Fab")
		)
		(fp_line
			(start -0.67945 -0.305054)
			(end -0.12065 -0.305054)
			(stroke
				(width 0.1)
				(type default)
			)
			(layer "F.Fab")
		)
		(fp_line
			(start 0.67945 -0.3048)
			(end 0.67945 0.3048)
			(stroke
				(width 0.1)
				(type default)
			)
			(layer "F.Fab")
		)
		(fp_line
			(start 0.12065 -0.3048)
			(end 0.67945 -0.3048)
			(stroke
				(width 0.1)
				(type default)
			)
			(layer "F.Fab")
		)
		(fp_line
			(start 0.12065 -0.2794)
			(end 0.12065 -0.3048)
			(stroke
				(width 0.1)
				(type default)
			)
			(layer "F.Fab")
		)
		(fp_line
			(start -0.12065 -0.2794)
			(end 0.12065 -0.2794)
			(stroke
				(width 0.1)
				(type default)
			)
			(layer "F.Fab")
		)
		(fp_line
			(start 0.120396 0.2794)
			(end -0.12065 0.2794)
			(stroke
				(width 0.1)
				(type default)
			)
			(layer "F.Fab")
		)
		(fp_line
			(start -0.12065 0.2794)
			(end -0.12065 0.3048)
			(stroke
				(width 0.1)
				(type default)
			)
			(layer "F.Fab")
		)
		(fp_line
			(start 0.67945 0.3048)
			(end 0.120396 0.3048)
			(stroke
				(width 0.1)
				(type default)
			)
			(layer "F.Fab")
		)
		(fp_line
			(start 0.120396 0.3048)
			(end 0.120396 0.2794)
			(stroke
				(width 0.1)
				(type default)
			)
			(layer "F.Fab")
		)
		(fp_line
			(start -0.12065 0.3048)
			(end -0.67945 0.3048)
			(stroke
				(width 0.1)
				(type default)
			)
			(layer "F.Fab")
		)
		(fp_line
			(start -0.67945 0.3048)
			(end -0.67945 -0.305054)
			(stroke
				(width 0.1)
				(type default)
			)
			(layer "F.Fab")
		)
		(pad "1" smd circle
			(at -0.40005 0 90)
			(size 0 0)
			(layers "F.Cu" "F.Mask" "F.Paste")
			(net "P12V_OCP_ISET_1")
		)
		(pad "2" smd circle
			(at 0.40005 0 90)
			(size 0 0)
			(layers "F.Cu" "F.Mask" "F.Paste")
			(net "GND")
		)
	)
)
